(kicad_pcb
	(version 20260206)
	(generator "pcbnew")
	(generator_version "10.0")
	(general
		(thickness 1.6)
		(legacy_teardrops no)
	)
	(paper "A4")
	(title_block
		(title "fcb — Lightning_FCB_BRD.brd")
		(comment 1 "Lightning (Wiwynn / Facebook NVMe JBOF) / footprints 275-282 of 495")
	)
	(layers
		(0 "F.Cu" signal "TOP")
		(4 "In1.Cu" signal "L2GND")
		(6 "In2.Cu" signal "L3VCC")
		(2 "B.Cu" signal "BOTTOM")
		(9 "F.Adhes" user "F.Adhesive")
		(11 "B.Adhes" user "B.Adhesive")
		(13 "F.Paste" user "Package Geometry/Pastemask Top")
		(15 "B.Paste" user "Package Geometry/Pastemask Bottom")
		(5 "F.SilkS" user "Ref Des/Silkscreen Top")
		(7 "B.SilkS" user "Ref Des/Silkscreen Bottom")
		(1 "F.Mask" user "Board Geometry/Soldermask Top")
		(3 "B.Mask" user "Board Geometry/Soldermask Bottom")
		(17 "Dwgs.User" user "User.Drawings")
		(19 "Cmts.User" user "User.Comments")
		(21 "Eco1.User" user "User.Eco1")
		(23 "Eco2.User" user "User.Eco2")
		(25 "Edge.Cuts" user "Board Geometry/Outline")
		(27 "Margin" user)
		(31 "F.CrtYd" user "Package Geometry/Place Bound Top")
		(29 "B.CrtYd" user "Package Geometry/Place Bound Bottom")
		(35 "F.Fab" user "Ref Des/Assembly Top")
		(33 "B.Fab" user "Ref Des/Assembly Bottom")
	)
	(footprint ""
		(layer "F.Cu")
		(at 17.9832 -248.5644 180)
		(property "Reference" "PR52"
			(at 0 0 180)
			(layer "F.SilkS")
			(hide yes)
			(effects
				(font
					(size 1.27 1.27)
				)
			)
		)
		(property "Value" "47KR3F-GP"
			(at -0.0254 -2.5146 180)
			(unlocked yes)
			(layer "F.Fab")
			(hide yes)
			(effects
				(font
					(size 1.016 1.016)
					(thickness 0.1524)
				)
			)
		)
		(property "Device Type" "R603H22"
			(at -0.0254 -4.0386 180)
			(unlocked yes)
			(layer "F.Fab")
			(hide yes)
			(effects
				(font
					(size 1.016 1.016)
					(thickness 0.1524)
				)
			)
		)
		(duplicate_pad_numbers_are_jumpers no)
		(fp_line
			(start 0.2032 0)
			(end 0.4826 0)
			(stroke
				(width 0.2032)
				(type default)
			)
			(layer "F.SilkS")
		)
		(fp_line
			(start -0.4826 0)
			(end -0.2032 0)
			(stroke
				(width 0.2032)
				(type default)
			)
			(layer "F.SilkS")
		)
		(fp_rect
			(start -0.5842 1.3335)
			(end 0.5842 -1.3335)
			(stroke
				(width 0)
				(type default)
			)
			(fill no)
			(layer "F.CrtYd")
		)
		(fp_rect
			(start -0.5842 1.3335)
			(end 0.5842 -1.3335)
			(stroke
				(width 0)
				(type default)
			)
			(fill no)
			(layer "F.Fab")
		)
		(pad "1" smd custom
			(at 0 -0.762 180)
			(size 0.2159 0.2159)
			(layers "F.Cu" "F.Mask" "F.Paste")
			(net "P3V3_IN")
			(options
				(clearance outline)
				(anchor circle)
			)
			(primitives
				(gr_poly
					(pts
						(arc
							(start -0.3302 -0.4318)
							(mid -0.402042 -0.402042)
							(end -0.4318 -0.3302)
						)
						(arc
							(start -0.4318 0.3302)
							(mid -0.402042 0.402042)
							(end -0.3302 0.4318)
						)
						(arc
							(start 0.3302 0.4318)
							(mid 0.402042 0.402042)
							(end 0.4318 0.3302)
						)
						(arc
							(start 0.4318 -0.3302)
							(mid 0.402042 -0.402042)
							(end 0.3302 -0.4318)
						)
					)
					(width 0)
					(fill yes)
				)
			)
		)
		(pad "2" smd custom
			(at 0 0.762 180)
			(size 0.2159 0.2159)
			(layers "F.Cu" "F.Mask" "F.Paste")
			(net "P3V3_EN")
			(options
				(clearance outline)
				(anchor circle)
			)
			(primitives
				(gr_poly
					(pts
						(arc
							(start -0.3302 -0.4318)
							(mid -0.402042 -0.402042)
							(end -0.4318 -0.3302)
						)
						(arc
							(start -0.4318 0.3302)
							(mid -0.402042 0.402042)
							(end -0.3302 0.4318)
						)
						(arc
							(start 0.3302 0.4318)
							(mid 0.402042 0.402042)
							(end 0.4318 0.3302)
						)
						(arc
							(start 0.4318 -0.3302)
							(mid 0.402042 -0.402042)
							(end 0.3302 -0.4318)
						)
					)
					(width 0)
					(fill yes)
				)
			)
		)
	)
	(footprint ""
		(layer "F.Cu")
		(at 21.489162 -13.843508 90)
		(property "Reference" "D3"
			(at 0 0 90)
			(layer "F.SilkS")
			(hide yes)
			(effects
				(font
					(size 1.27 1.27)
				)
			)
		)
		(property "Value" "BAS16H-GP"
			(at 0 -5.5372 90)
			(unlocked yes)
			(layer "F.Fab")
			(hide yes)
			(effects
				(font
					(size 1.016 1.016)
					(thickness 0.1524)
				)
			)
		)
		(property "Device Type" "SOD123AKH48"
			(at 0 -7.0612 90)
			(unlocked yes)
			(layer "F.Fab")
			(hide yes)
			(effects
				(font
					(size 1.016 1.016)
					(thickness 0.1524)
				)
			)
		)
		(duplicate_pad_numbers_are_jumpers no)
		(fp_line
			(start 1.016 -2.667)
			(end -1.016 -2.667)
			(stroke
				(width 0.1524)
				(type default)
			)
			(layer "F.SilkS")
		)
		(fp_line
			(start -1.016 -2.667)
			(end -1.016 2.667)
			(stroke
				(width 0.1524)
				(type default)
			)
			(layer "F.SilkS")
		)
		(fp_line
			(start 1.016 2.667)
			(end 1.016 -2.667)
			(stroke
				(width 0.1524)
				(type default)
			)
			(layer "F.SilkS")
		)
		(fp_line
			(start -1.016 2.667)
			(end 1.016 2.667)
			(stroke
				(width 0.1524)
				(type default)
			)
			(layer "F.SilkS")
		)
		(fp_line
			(start 0.889 2.921)
			(end -0.889 2.921)
			(stroke
				(width 0.508)
				(type default)
			)
			(layer "F.SilkS")
		)
		(fp_rect
			(start -1.143 3.175)
			(end 1.143 -2.794)
			(stroke
				(width 0)
				(type default)
			)
			(fill no)
			(layer "F.CrtYd")
		)
		(fp_poly
			(pts
				(xy -1.143 -2.794) (xy 1.143 -2.794) (xy 1.143 3.175) (xy -1.143 3.175)
			)
			(stroke
				(width 0)
				(type default)
			)
			(fill no)
			(layer "F.Fab")
		)
		(pad "A" smd rect
			(at 0 -1.6891 90)
			(size 0.889 1.397)
			(layers "F.Cu" "F.Mask" "F.Paste")
			(net "FAN_TACH11")
		)
		(pad "K" smd rect
			(at 0 1.6891 90)
			(size 0.889 1.397)
			(layers "F.Cu" "F.Mask" "F.Paste")
			(net "P12V")
		)
	)
	(footprint ""
		(layer "F.Cu")
		(at 12.2682 -445.516 180)
		(property "Reference" "R97"
			(at 0 0 180)
			(layer "F.SilkS")
			(hide yes)
			(effects
				(font
					(size 1.27 1.27)
				)
			)
		)
		(property "Value" "4K7R2F-GP"
			(at 0.064008 -3.993896 180)
			(unlocked yes)
			(layer "F.Fab")
			(hide yes)
			(effects
				(font
					(size 1.016 1.016)
					(thickness 0.1524)
				)
			)
		)
		(property "Device Type" "R402H16"
			(at 0.064008 -5.517896 180)
			(unlocked yes)
			(layer "F.Fab")
			(hide yes)
			(effects
				(font
					(size 1.016 1.016)
					(thickness 0.1524)
				)
			)
		)
		(duplicate_pad_numbers_are_jumpers no)
		(fp_line
			(start 0.508 -0.9398)
			(end -0.508 -0.9398)
			(stroke
				(width 0.1524)
				(type default)
			)
			(layer "F.SilkS")
		)
		(fp_line
			(start -0.508 -0.9398)
			(end -0.508 0.9398)
			(stroke
				(width 0.1524)
				(type default)
			)
			(layer "F.SilkS")
		)
		(fp_rect
			(start -0.508 0.9398)
			(end 0.508 -0.9398)
			(stroke
				(width 0)
				(type default)
			)
			(fill no)
			(layer "F.CrtYd")
		)
		(fp_rect
			(start -0.508 0.9398)
			(end 0.508 -0.9398)
			(stroke
				(width 0)
				(type default)
			)
			(fill no)
			(layer "F.Fab")
		)
		(pad "1" smd custom
			(at 0 -0.4445 180)
			(size 0.1397 0.1397)
			(layers "F.Cu" "F.Mask" "F.Paste")
			(net "P12V")
			(options
				(clearance outline)
				(anchor circle)
			)
			(primitives
				(gr_poly
					(pts
						(arc
							(start -0.1778 -0.2794)
							(mid -0.249642 -0.249642)
							(end -0.2794 -0.1778)
						)
						(arc
							(start -0.2794 0.1778)
							(mid -0.249642 0.249642)
							(end -0.1778 0.2794)
						)
						(arc
							(start 0.1778 0.2794)
							(mid 0.249642 0.249642)
							(end 0.2794 0.1778)
						)
						(arc
							(start 0.2794 -0.1778)
							(mid 0.249642 -0.249642)
							(end 0.1778 -0.2794)
						)
					)
					(width 0)
					(fill yes)
				)
			)
		)
		(pad "2" smd custom
			(at 0 0.4445 180)
			(size 0.1397 0.1397)
			(layers "F.Cu" "F.Mask" "F.Paste")
			(net "FAN_TACH2")
			(options
				(clearance outline)
				(anchor circle)
			)
			(primitives
				(gr_poly
					(pts
						(arc
							(start -0.1778 -0.2794)
							(mid -0.249642 -0.249642)
							(end -0.2794 -0.1778)
						)
						(arc
							(start -0.2794 0.1778)
							(mid -0.249642 0.249642)
							(end -0.1778 0.2794)
						)
						(arc
							(start 0.1778 0.2794)
							(mid 0.249642 0.249642)
							(end 0.2794 0.1778)
						)
						(arc
							(start 0.2794 -0.1778)
							(mid 0.249642 -0.249642)
							(end 0.1778 -0.2794)
						)
					)
					(width 0)
					(fill yes)
				)
			)
		)
	)
	(footprint ""
		(layer "F.Cu")
		(at 26.035 -268.8336 90)
		(property "Reference" "C40"
			(at 0 0 90)
			(layer "F.SilkS")
			(hide yes)
			(effects
				(font
					(size 1.27 1.27)
				)
			)
		)
		(property "Value" "SC1U25V3KX-1-GP"
			(at 0 -2.8194 90)
			(unlocked yes)
			(layer "F.Fab")
			(hide yes)
			(effects
				(font
					(size 1.016 1.016)
					(thickness 0.1524)
				)
			)
		)
		(property "Device Type" "C603H36"
			(at 0 -4.3434 90)
			(unlocked yes)
			(layer "F.Fab")
			(hide yes)
			(effects
				(font
					(size 1.016 1.016)
					(thickness 0.1524)
				)
			)
		)
		(duplicate_pad_numbers_are_jumpers no)
		(fp_line
			(start 0.508 0)
			(end -0.508 0)
			(stroke
				(width 0.2032)
				(type default)
			)
			(layer "F.SilkS")
		)
		(fp_rect
			(start -0.5842 1.3335)
			(end 0.5842 -1.3335)
			(stroke
				(width 0)
				(type default)
			)
			(fill no)
			(layer "F.CrtYd")
		)
		(fp_rect
			(start -0.5842 1.3335)
			(end 0.5842 -1.3335)
			(stroke
				(width 0)
				(type default)
			)
			(fill no)
			(layer "F.Fab")
		)
		(pad "1" smd custom
			(at 0 -0.762 90)
			(size 0.2159 0.2159)
			(layers "F.Cu" "F.Mask" "F.Paste")
			(net "P12V")
			(options
				(clearance outline)
				(anchor circle)
			)
			(primitives
				(gr_poly
					(pts
						(arc
							(start -0.3302 -0.4318)
							(mid -0.402042 -0.402042)
							(end -0.4318 -0.3302)
						)
						(arc
							(start -0.4318 0.3302)
							(mid -0.402042 0.402042)
							(end -0.3302 0.4318)
						)
						(arc
							(start 0.3302 0.4318)
							(mid 0.402042 0.402042)
							(end 0.4318 0.3302)
						)
						(arc
							(start 0.4318 -0.3302)
							(mid 0.402042 -0.402042)
							(end 0.3302 -0.4318)
						)
					)
					(width 0)
					(fill yes)
				)
			)
		)
		(pad "2" smd custom
			(at 0 0.762 90)
			(size 0.2159 0.2159)
			(layers "F.Cu" "F.Mask" "F.Paste")
			(net "GND")
			(options
				(clearance outline)
				(anchor circle)
			)
			(primitives
				(gr_poly
					(pts
						(arc
							(start -0.3302 -0.4318)
							(mid -0.402042 -0.402042)
							(end -0.4318 -0.3302)
						)
						(arc
							(start -0.4318 0.3302)
							(mid -0.402042 0.402042)
							(end -0.3302 0.4318)
						)
						(arc
							(start 0.3302 0.4318)
							(mid 0.402042 0.402042)
							(end 0.4318 0.3302)
						)
						(arc
							(start 0.4318 -0.3302)
							(mid 0.402042 -0.402042)
							(end 0.3302 -0.4318)
						)
					)
					(width 0)
					(fill yes)
				)
			)
		)
	)
	(footprint ""
		(layer "F.Cu")
		(at 37.973 -180.34)
		(property "Reference" "R261"
			(at 0 0 0)
			(layer "F.SilkS")
			(hide yes)
			(effects
				(font
					(size 1.27 1.27)
				)
			)
		)
		(property "Value" "10KR2J-3-GP"
			(at 0.064008 -3.993896 0)
			(unlocked yes)
			(layer "F.Fab")
			(hide yes)
			(effects
				(font
					(size 1.016 1.016)
					(thickness 0.1524)
				)
			)
		)
		(property "Device Type" "R402H16"
			(at 0.064008 -5.517896 0)
			(unlocked yes)
			(layer "F.Fab")
			(hide yes)
			(effects
				(font
					(size 1.016 1.016)
					(thickness 0.1524)
				)
			)
		)
		(duplicate_pad_numbers_are_jumpers no)
		(fp_line
			(start -0.508 -0.9398)
			(end -0.508 0.9398)
			(stroke
				(width 0.1524)
				(type default)
			)
			(layer "F.SilkS")
		)
		(fp_line
			(start 0.508 -0.9398)
			(end -0.508 -0.9398)
			(stroke
				(width 0.1524)
				(type default)
			)
			(layer "F.SilkS")
		)
		(fp_rect
			(start -0.508 0.9398)
			(end 0.508 -0.9398)
			(stroke
				(width 0)
				(type default)
			)
			(fill no)
			(layer "F.CrtYd")
		)
		(fp_rect
			(start -0.508 0.9398)
			(end 0.508 -0.9398)
			(stroke
				(width 0)
				(type default)
			)
			(fill no)
			(layer "F.Fab")
		)
		(pad "1" smd custom
			(at 0 -0.4445)
			(size 0.1397 0.1397)
			(layers "F.Cu" "F.Mask" "F.Paste")
			(net "D_LATCH_CLR")
			(options
				(clearance outline)
				(anchor circle)
			)
			(primitives
				(gr_poly
					(pts
						(arc
							(start -0.1778 -0.2794)
							(mid -0.249642 -0.249642)
							(end -0.2794 -0.1778)
						)
						(arc
							(start -0.2794 0.1778)
							(mid -0.249642 0.249642)
							(end -0.1778 0.2794)
						)
						(arc
							(start 0.1778 0.2794)
							(mid 0.249642 0.249642)
							(end 0.2794 0.1778)
						)
						(arc
							(start 0.2794 -0.1778)
							(mid 0.249642 -0.249642)
							(end 0.1778 -0.2794)
						)
					)
					(width 0)
					(fill yes)
				)
			)
		)
		(pad "2" smd custom
			(at 0 0.4445)
			(size 0.1397 0.1397)
			(layers "F.Cu" "F.Mask" "F.Paste")
			(net "P3V3_AUX")
			(options
				(clearance outline)
				(anchor circle)
			)
			(primitives
				(gr_poly
					(pts
						(arc
							(start -0.1778 -0.2794)
							(mid -0.249642 -0.249642)
							(end -0.2794 -0.1778)
						)
						(arc
							(start -0.2794 0.1778)
							(mid -0.249642 0.249642)
							(end -0.1778 0.2794)
						)
						(arc
							(start 0.1778 0.2794)
							(mid 0.249642 0.249642)
							(end 0.2794 0.1778)
						)
						(arc
							(start 0.2794 -0.1778)
							(mid 0.249642 -0.249642)
							(end 0.1778 -0.2794)
						)
					)
					(width 0)
					(fill yes)
				)
			)
		)
	)
	(footprint ""
		(layer "F.Cu")
		(at 38.227 -178.054 180)
		(property "Reference" "C254"
			(at 0 0 180)
			(layer "F.SilkS")
			(hide yes)
			(effects
				(font
					(size 1.27 1.27)
				)
			)
		)
		(property "Value" "SCD1U16V2KX-3GP"
			(at 1.1811 -2.7051 180)
			(unlocked yes)
			(layer "F.Fab")
			(hide yes)
			(effects
				(font
					(size 1.016 1.016)
					(thickness 0.1524)
				)
			)
		)
		(property "Device Type" "C402H22"
			(at 1.1811 -4.2291 180)
			(unlocked yes)
			(layer "F.Fab")
			(hide yes)
			(effects
				(font
					(size 1.016 1.016)
					(thickness 0.1524)
				)
			)
		)
		(duplicate_pad_numbers_are_jumpers no)
		(fp_rect
			(start -0.4318 0.9525)
			(end 0.4318 -0.9525)
			(stroke
				(width 0)
				(type default)
			)
			(fill no)
			(layer "F.CrtYd")
		)
		(fp_rect
			(start -0.4318 0.9525)
			(end 0.4318 -0.9525)
			(stroke
				(width 0)
				(type default)
			)
			(fill no)
			(layer "F.Fab")
		)
		(pad "1" smd custom
			(at 0 -0.4445 180)
			(size 0.1524 0.1524)
			(layers "F.Cu" "F.Mask" "F.Paste")
			(net "P3V3_AUX")
			(options
				(clearance outline)
				(anchor circle)
			)
			(primitives
				(gr_poly
					(pts
						(arc
							(start 0.3048 -0.2032)
							(mid 0.275042 -0.275042)
							(end 0.2032 -0.3048)
						)
						(arc
							(start -0.2032 -0.3048)
							(mid -0.275042 -0.275042)
							(end -0.3048 -0.2032)
						)
						(arc
							(start -0.3048 0.2032)
							(mid -0.275042 0.275042)
							(end -0.2032 0.3048)
						)
						(arc
							(start 0.2032 0.3048)
							(mid 0.275042 0.275042)
							(end 0.3048 0.2032)
						)
					)
					(width 0)
					(fill yes)
				)
			)
		)
		(pad "2" smd custom
			(at 0 0.4445 180)
			(size 0.1524 0.1524)
			(layers "F.Cu" "F.Mask" "F.Paste")
			(net "GND")
			(options
				(clearance outline)
				(anchor circle)
			)
			(primitives
				(gr_poly
					(pts
						(arc
							(start 0.3048 -0.2032)
							(mid 0.275042 -0.275042)
							(end 0.2032 -0.3048)
						)
						(arc
							(start -0.2032 -0.3048)
							(mid -0.275042 -0.275042)
							(end -0.3048 -0.2032)
						)
						(arc
							(start -0.3048 0.2032)
							(mid -0.275042 0.275042)
							(end -0.2032 0.3048)
						)
						(arc
							(start 0.2032 0.3048)
							(mid 0.275042 0.275042)
							(end 0.3048 0.2032)
						)
					)
					(width 0)
					(fill yes)
				)
			)
		)
	)
	(footprint ""
		(layer "F.Cu")
		(at 40.851074 -362.859574 180)
		(property "Reference" "PR41"
			(at 0 0 180)
			(layer "F.SilkS")
			(hide yes)
			(effects
				(font
					(size 1.27 1.27)
				)
			)
		)
		(property "Value" "1KR2F-3-GP"
			(at 0.064008 -3.993896 180)
			(unlocked yes)
			(layer "F.Fab")
			(hide yes)
			(effects
				(font
					(size 1.016 1.016)
					(thickness 0.1524)
				)
			)
		)
		(property "Device Type" "R402H16"
			(at 0.064008 -5.517896 180)
			(unlocked yes)
			(layer "F.Fab")
			(hide yes)
			(effects
				(font
					(size 1.016 1.016)
					(thickness 0.1524)
				)
			)
		)
		(duplicate_pad_numbers_are_jumpers no)
		(fp_line
			(start 0.508 -0.9398)
			(end -0.508 -0.9398)
			(stroke
				(width 0.1524)
				(type default)
			)
			(layer "F.SilkS")
		)
		(fp_line
			(start -0.508 -0.9398)
			(end -0.508 0.9398)
			(stroke
				(width 0.1524)
				(type default)
			)
			(layer "F.SilkS")
		)
		(fp_rect
			(start -0.508 0.9398)
			(end 0.508 -0.9398)
			(stroke
				(width 0)
				(type default)
			)
			(fill no)
			(layer "F.CrtYd")
		)
		(fp_rect
			(start -0.508 0.9398)
			(end 0.508 -0.9398)
			(stroke
				(width 0)
				(type default)
			)
			(fill no)
			(layer "F.Fab")
		)
		(pad "1" smd custom
			(at 0 -0.4445 180)
			(size 0.1397 0.1397)
			(layers "F.Cu" "F.Mask" "F.Paste")
			(net "TEMP_ALM#_JP_1")
			(options
				(clearance outline)
				(anchor circle)
			)
			(primitives
				(gr_poly
					(pts
						(arc
							(start -0.1778 -0.2794)
							(mid -0.249642 -0.249642)
							(end -0.2794 -0.1778)
						)
						(arc
							(start -0.2794 0.1778)
							(mid -0.249642 0.249642)
							(end -0.1778 0.2794)
						)
						(arc
							(start 0.1778 0.2794)
							(mid 0.249642 0.249642)
							(end 0.2794 0.1778)
						)
						(arc
							(start 0.2794 -0.1778)
							(mid 0.249642 -0.249642)
							(end 0.1778 -0.2794)
						)
					)
					(width 0)
					(fill yes)
				)
			)
		)
		(pad "2" smd custom
			(at 0 0.4445 180)
			(size 0.1397 0.1397)
			(layers "F.Cu" "F.Mask" "F.Paste")
			(net "ADM1276_LATCH#")
			(options
				(clearance outline)
				(anchor circle)
			)
			(primitives
				(gr_poly
					(pts
						(arc
							(start -0.1778 -0.2794)
							(mid -0.249642 -0.249642)
							(end -0.2794 -0.1778)
						)
						(arc
							(start -0.2794 0.1778)
							(mid -0.249642 0.249642)
							(end -0.1778 0.2794)
						)
						(arc
							(start 0.1778 0.2794)
							(mid 0.249642 0.249642)
							(end 0.2794 0.1778)
						)
						(arc
							(start 0.2794 -0.1778)
							(mid 0.249642 -0.249642)
							(end 0.1778 -0.2794)
						)
					)
					(width 0)
					(fill yes)
				)
			)
		)
	)
	(footprint ""
		(layer "F.Cu")
		(at 29.6672 -149.071584 180)
		(property "Reference" "R16"
			(at 0 0 180)
			(layer "F.SilkS")
			(hide yes)
			(effects
				(font
					(size 1.27 1.27)
				)
			)
		)
		(property "Value" "110KR2F-L-GP"
			(at 0.064008 -3.993896 180)
			(unlocked yes)
			(layer "F.Fab")
			(hide yes)
			(effects
				(font
					(size 1.016 1.016)
					(thickness 0.1524)
				)
			)
		)
		(property "Device Type" "R402H16"
			(at 0.064008 -5.517896 180)
			(unlocked yes)
			(layer "F.Fab")
			(hide yes)
			(effects
				(font
					(size 1.016 1.016)
					(thickness 0.1524)
				)
			)
		)
		(duplicate_pad_numbers_are_jumpers no)
		(fp_line
			(start 0.508 -0.9398)
			(end -0.508 -0.9398)
			(stroke
				(width 0.1524)
				(type default)
			)
			(layer "F.SilkS")
		)
		(fp_line
			(start -0.508 -0.9398)
			(end -0.508 0.9398)
			(stroke
				(width 0.1524)
				(type default)
			)
			(layer "F.SilkS")
		)
		(fp_rect
			(start -0.508 0.9398)
			(end 0.508 -0.9398)
			(stroke
				(width 0)
				(type default)
			)
			(fill no)
			(layer "F.CrtYd")
		)
		(fp_rect
			(start -0.508 0.9398)
			(end 0.508 -0.9398)
			(stroke
				(width 0)
				(type default)
			)
			(fill no)
			(layer "F.Fab")
		)
		(pad "1" smd custom
			(at 0 -0.4445 180)
			(size 0.1397 0.1397)
			(layers "F.Cu" "F.Mask" "F.Paste")
			(net "P12VL")
			(options
				(clearance outline)
				(anchor circle)
			)
			(primitives
				(gr_poly
					(pts
						(arc
							(start -0.1778 -0.2794)
							(mid -0.249642 -0.249642)
							(end -0.2794 -0.1778)
						)
						(arc
							(start -0.2794 0.1778)
							(mid -0.249642 0.249642)
							(end -0.1778 0.2794)
						)
						(arc
							(start 0.1778 0.2794)
							(mid 0.249642 0.249642)
							(end 0.2794 0.1778)
						)
						(arc
							(start 0.2794 -0.1778)
							(mid 0.249642 -0.249642)
							(end 0.1778 -0.2794)
						)
					)
					(width 0)
					(fill yes)
				)
			)
		)
		(pad "2" smd custom
			(at 0 0.4445 180)
			(size 0.1397 0.1397)
			(layers "F.Cu" "F.Mask" "F.Paste")
			(net "NCT7904_VSEN6")
			(options
				(clearance outline)
				(anchor circle)
			)
			(primitives
				(gr_poly
					(pts
						(arc
							(start -0.1778 -0.2794)
							(mid -0.249642 -0.249642)
							(end -0.2794 -0.1778)
						)
						(arc
							(start -0.2794 0.1778)
							(mid -0.249642 0.249642)
							(end -0.1778 0.2794)
						)
						(arc
							(start 0.1778 0.2794)
							(mid 0.249642 0.249642)
							(end 0.2794 0.1778)
						)
						(arc
							(start 0.2794 -0.1778)
							(mid 0.249642 -0.249642)
							(end 0.1778 -0.2794)
						)
					)
					(width 0)
					(fill yes)
				)
			)
		)
	)
)
